(kicad_pcb
	(version 20260206)
	(generator "pcbnew")
	(generator_version "10.0")
	(general
		(thickness 1.6)
		(legacy_teardrops no)
	)
	(paper "A4")
	(title_block
		(title "15969-1a.1015WZS0858.brd")
		(comment 1 "Tioga Pass / footprints 181-187 of 295")
	)
	(layers
		(0 "F.Cu" signal "TOP")
		(4 "In1.Cu" signal "L2GND")
		(6 "In2.Cu" signal "L3")
		(8 "In3.Cu" signal "L4")
		(10 "In4.Cu" signal "L5GND")
		(2 "B.Cu" signal "BOTTOM")
		(9 "F.Adhes" user "F.Adhesive")
		(11 "B.Adhes" user "B.Adhesive")
		(13 "F.Paste" user "Package Geometry/Pastemask Top")
		(15 "B.Paste" user "Package Geometry/Pastemask Bottom")
		(5 "F.SilkS" user "Ref Des/Silkscreen Top")
		(7 "B.SilkS" user "Ref Des/Silkscreen Bottom")
		(1 "F.Mask" user "Board Geometry/Soldermask Top")
		(3 "B.Mask" user "Board Geometry/Soldermask Bottom")
		(17 "Dwgs.User" user "User.Drawings")
		(19 "Cmts.User" user "User.Comments")
		(21 "Eco1.User" user "User.Eco1")
		(23 "Eco2.User" user "User.Eco2")
		(25 "Edge.Cuts" user "Board Geometry/Outline")
		(27 "Margin" user)
		(31 "F.CrtYd" user "Package Geometry/Place Bound Top")
		(29 "B.CrtYd" user "Package Geometry/Place Bound Bottom")
		(35 "F.Fab" user "Ref Des/Assembly Top")
		(33 "B.Fab" user "Ref Des/Assembly Bottom")
	)
	(footprint ""
		(layer "B.Cu")
		(at 115.54968 -3.53568)
		(property "Reference" "R55"
			(at 0 0 0)
			(layer "B.SilkS")
			(hide yes)
			(effects
				(font
					(size 1.27 1.27)
				)
				(justify mirror)
			)
		)
		(property "Value" "10KR2F-2-GP"
			(at -0.064008 -3.993896 0)
			(unlocked yes)
			(layer "B.Fab")
			(hide yes)
			(effects
				(font
					(size 1.016 1.016)
					(thickness 0.1524)
				)
				(justify mirror)
			)
		)
		(property "Device Type" "R402H16"
			(at -0.064008 -5.517896 0)
			(unlocked yes)
			(layer "B.Fab")
			(hide yes)
			(effects
				(font
					(size 1.016 1.016)
					(thickness 0.1524)
				)
				(justify mirror)
			)
		)
		(duplicate_pad_numbers_are_jumpers no)
		(fp_line
			(start -0.508 -0.9398)
			(end 0.508 -0.9398)
			(stroke
				(width 0.1524)
				(type default)
			)
			(layer "B.SilkS")
		)
		(fp_line
			(start 0.508 -0.9398)
			(end 0.508 0.9398)
			(stroke
				(width 0.1524)
				(type default)
			)
			(layer "B.SilkS")
		)
		(fp_rect
			(start 0.508 0.9398)
			(end -0.508 -0.9398)
			(stroke
				(width 0)
				(type default)
			)
			(fill no)
			(layer "B.CrtYd")
		)
		(fp_rect
			(start 0.508 0.9398)
			(end -0.508 -0.9398)
			(stroke
				(width 0)
				(type default)
			)
			(fill no)
			(layer "B.Fab")
		)
		(pad "1" smd custom
			(at 0 -0.4445 180)
			(size 0.1397 0.1397)
			(layers "B.Cu" "B.Mask" "B.Paste")
			(net "SMB_PCIE_SLOT3_ALERT_N")
			(options
				(clearance outline)
				(anchor circle)
			)
			(primitives
				(gr_poly
					(pts
						(arc
							(start -0.1778 0.2794)
							(mid -0.249642 0.249642)
							(end -0.2794 0.1778)
						)
						(arc
							(start -0.2794 -0.1778)
							(mid -0.249642 -0.249642)
							(end -0.1778 -0.2794)
						)
						(arc
							(start 0.1778 -0.2794)
							(mid 0.249642 -0.249642)
							(end 0.2794 -0.1778)
						)
						(arc
							(start 0.2794 0.1778)
							(mid 0.249642 0.249642)
							(end 0.1778 0.2794)
						)
					)
					(width 0)
					(fill yes)
				)
			)
		)
		(pad "2" smd custom
			(at 0 0.4445 180)
			(size 0.1397 0.1397)
			(layers "B.Cu" "B.Mask" "B.Paste")
			(net "P3V3_STBY")
			(options
				(clearance outline)
				(anchor circle)
			)
			(primitives
				(gr_poly
					(pts
						(arc
							(start -0.1778 0.2794)
							(mid -0.249642 0.249642)
							(end -0.2794 0.1778)
						)
						(arc
							(start -0.2794 -0.1778)
							(mid -0.249642 -0.249642)
							(end -0.1778 -0.2794)
						)
						(arc
							(start 0.1778 -0.2794)
							(mid 0.249642 -0.249642)
							(end 0.2794 -0.1778)
						)
						(arc
							(start 0.2794 0.1778)
							(mid 0.249642 0.249642)
							(end 0.1778 0.2794)
						)
					)
					(width 0)
					(fill yes)
				)
			)
		)
	)
	(footprint ""
		(layer "B.Cu")
		(at 124.5362 -15.9258 90)
		(property "Reference" "U24"
			(at 0 0 90)
			(layer "B.SilkS")
			(hide yes)
			(effects
				(font
					(size 1.27 1.27)
				)
				(justify mirror)
			)
		)
		(property "Value" "TCA9517DGKR-GP"
			(at 0.1143 -9.1948 90)
			(unlocked yes)
			(layer "B.Fab")
			(hide yes)
			(effects
				(font
					(size 1.016 1.016)
					(thickness 0.1524)
				)
				(justify mirror)
			)
		)
		(property "Device Type" "MSOP8-1H44"
			(at 0.1143 -10.795 90)
			(unlocked yes)
			(layer "B.Fab")
			(hide yes)
			(effects
				(font
					(size 1.016 1.016)
					(thickness 0.1524)
				)
				(justify mirror)
			)
		)
		(duplicate_pad_numbers_are_jumpers no)
		(fp_line
			(start 1.9558 -1.016)
			(end 1.9558 1.016)
			(stroke
				(width 0.1524)
				(type default)
			)
			(layer "B.SilkS")
		)
		(fp_line
			(start -1.0795 -1.016)
			(end 1.9558 -1.016)
			(stroke
				(width 0.1524)
				(type default)
			)
			(layer "B.SilkS")
		)
		(fp_line
			(start 1.9558 -0.5461)
			(end 1.4478 -0.0381)
			(stroke
				(width 0.1524)
				(type default)
			)
			(layer "B.SilkS")
		)
		(fp_line
			(start 1.4478 -0.0381)
			(end 1.9558 0.4699)
			(stroke
				(width 0.1524)
				(type default)
			)
			(layer "B.SilkS")
		)
		(fp_line
			(start 1.9558 1.016)
			(end -1.0795 1.016)
			(stroke
				(width 0.1524)
				(type default)
			)
			(layer "B.SilkS")
		)
		(fp_line
			(start -1.0795 1.016)
			(end -1.0795 -1.016)
			(stroke
				(width 0.1524)
				(type default)
			)
			(layer "B.SilkS")
		)
		(fp_line
			(start 1.778 1.0922)
			(end 1.778 3.048)
			(stroke
				(width 0.508)
				(type default)
			)
			(layer "B.SilkS")
		)
		(fp_poly
			(pts
				(xy 1.1557 -1.016) (xy 1.1557 1.016) (xy -1.1557 1.016) (xy -1.1557 -1.016)
			)
			(stroke
				(width 0)
				(type default)
			)
			(fill yes)
			(layer "B.SilkS")
		)
		(fp_rect
			(start 1.4986 2.4511)
			(end -1.4986 -2.4511)
			(stroke
				(width 0)
				(type default)
			)
			(fill no)
			(layer "B.CrtYd")
		)
		(fp_poly
			(pts
				(xy 2.032 3.302) (xy 2.032 -3.302) (xy -2.032 -3.302) (xy -2.032 -2.1209) (xy -1.4986 -2.1209) (xy -1.4986 -2.4511)
				(xy 1.4986 -2.4511) (xy 1.4986 2.4511) (xy -1.4986 2.4511) (xy -1.4986 -2.1082) (xy -2.032 -2.1082)
				(xy -2.032 3.302)
			)
			(stroke
				(width 0)
				(type default)
			)
			(fill no)
			(layer "B.CrtYd")
		)
		(fp_rect
			(start 2.032 3.302)
			(end -2.032 -3.302)
			(stroke
				(width 0)
				(type default)
			)
			(fill no)
			(layer "B.Fab")
		)
		(pad "1" smd rect
			(at 0.97536 2.05486 270)
			(size 0.3556 1.524)
			(layers "B.Cu" "B.Mask" "B.Paste")
			(net "P3V3_STBY")
		)
		(pad "2" smd rect
			(at 0.32512 2.05486 270)
			(size 0.3556 1.524)
			(layers "B.Cu" "B.Mask" "B.Paste")
			(net "SMCLK_USB_HUB")
		)
		(pad "3" smd rect
			(at -0.32512 2.05486 270)
			(size 0.3556 1.524)
			(layers "B.Cu" "B.Mask" "B.Paste")
			(net "SMDAT_USB_HUB")
		)
		(pad "4" smd rect
			(at -0.97536 2.05486 270)
			(size 0.3556 1.524)
			(layers "B.Cu" "B.Mask" "B.Paste")
			(net "GND")
		)
		(pad "5" smd rect
			(at -0.97536 -2.05486 270)
			(size 0.3556 1.524)
			(layers "B.Cu" "B.Mask" "B.Paste")
			(net "SMB_U_REPEATER_EN")
		)
		(pad "6" smd rect
			(at -0.32512 -2.05486 270)
			(size 0.3556 1.524)
			(layers "B.Cu" "B.Mask" "B.Paste")
			(net "SMDAT_USB_HUB_R")
		)
		(pad "7" smd rect
			(at 0.32512 -2.05486 270)
			(size 0.3556 1.524)
			(layers "B.Cu" "B.Mask" "B.Paste")
			(net "SMCLK_USB_HUB_R")
		)
		(pad "8" smd rect
			(at 0.97536 -2.05486 270)
			(size 0.3556 1.524)
			(layers "B.Cu" "B.Mask" "B.Paste")
			(net "P3V3_USB_HUB")
		)
	)
	(footprint ""
		(layer "B.Cu")
		(at 121.9708 -9.8933 90)
		(property "Reference" "R38"
			(at 0 0 90)
			(layer "B.SilkS")
			(hide yes)
			(effects
				(font
					(size 1.27 1.27)
				)
				(justify mirror)
			)
		)
		(property "Value" "10KR2F-2-GP"
			(at -0.064008 -3.993896 90)
			(unlocked yes)
			(layer "B.Fab")
			(hide yes)
			(effects
				(font
					(size 1.016 1.016)
					(thickness 0.1524)
				)
				(justify mirror)
			)
		)
		(property "Device Type" "R402H16"
			(at -0.064008 -5.517896 90)
			(unlocked yes)
			(layer "B.Fab")
			(hide yes)
			(effects
				(font
					(size 1.016 1.016)
					(thickness 0.1524)
				)
				(justify mirror)
			)
		)
		(duplicate_pad_numbers_are_jumpers no)
		(fp_line
			(start 0.508 -0.9398)
			(end 0.508 0.9398)
			(stroke
				(width 0.1524)
				(type default)
			)
			(layer "B.SilkS")
		)
		(fp_line
			(start -0.508 -0.9398)
			(end 0.508 -0.9398)
			(stroke
				(width 0.1524)
				(type default)
			)
			(layer "B.SilkS")
		)
		(fp_rect
			(start 0.508 0.9398)
			(end -0.508 -0.9398)
			(stroke
				(width 0)
				(type default)
			)
			(fill no)
			(layer "B.CrtYd")
		)
		(fp_rect
			(start 0.508 0.9398)
			(end -0.508 -0.9398)
			(stroke
				(width 0)
				(type default)
			)
			(fill no)
			(layer "B.Fab")
		)
		(pad "1" smd custom
			(at 0 -0.4445 270)
			(size 0.1397 0.1397)
			(layers "B.Cu" "B.Mask" "B.Paste")
			(net "P3V3_STBY")
			(options
				(clearance outline)
				(anchor circle)
			)
			(primitives
				(gr_poly
					(pts
						(arc
							(start -0.1778 0.2794)
							(mid -0.249642 0.249642)
							(end -0.2794 0.1778)
						)
						(arc
							(start -0.2794 -0.1778)
							(mid -0.249642 -0.249642)
							(end -0.1778 -0.2794)
						)
						(arc
							(start 0.1778 -0.2794)
							(mid 0.249642 -0.249642)
							(end 0.2794 -0.1778)
						)
						(arc
							(start 0.2794 0.1778)
							(mid 0.249642 0.249642)
							(end 0.1778 0.2794)
						)
					)
					(width 0)
					(fill yes)
				)
			)
		)
		(pad "2" smd custom
			(at 0 0.4445 270)
			(size 0.1397 0.1397)
			(layers "B.Cu" "B.Mask" "B.Paste")
			(net "SMB_P_HUB_A1")
			(options
				(clearance outline)
				(anchor circle)
			)
			(primitives
				(gr_poly
					(pts
						(arc
							(start -0.1778 0.2794)
							(mid -0.249642 0.249642)
							(end -0.2794 0.1778)
						)
						(arc
							(start -0.2794 -0.1778)
							(mid -0.249642 -0.249642)
							(end -0.1778 -0.2794)
						)
						(arc
							(start 0.1778 -0.2794)
							(mid 0.249642 -0.249642)
							(end 0.2794 -0.1778)
						)
						(arc
							(start 0.2794 0.1778)
							(mid 0.249642 0.249642)
							(end 0.1778 0.2794)
						)
					)
					(width 0)
					(fill yes)
				)
			)
		)
	)
	(footprint ""
		(layer "B.Cu")
		(at 25.3238 -25.6032)
		(property "Reference" "R149"
			(at 0 0 0)
			(layer "B.SilkS")
			(hide yes)
			(effects
				(font
					(size 1.27 1.27)
				)
				(justify mirror)
			)
		)
		(property "Value" "10KR2F-2-GP"
			(at -0.064008 -3.993896 0)
			(unlocked yes)
			(layer "B.Fab")
			(hide yes)
			(effects
				(font
					(size 1.016 1.016)
					(thickness 0.1524)
				)
				(justify mirror)
			)
		)
		(property "Device Type" "R402H16"
			(at -0.064008 -5.517896 0)
			(unlocked yes)
			(layer "B.Fab")
			(hide yes)
			(effects
				(font
					(size 1.016 1.016)
					(thickness 0.1524)
				)
				(justify mirror)
			)
		)
		(duplicate_pad_numbers_are_jumpers no)
		(fp_line
			(start -0.508 -0.9398)
			(end 0.508 -0.9398)
			(stroke
				(width 0.1524)
				(type default)
			)
			(layer "B.SilkS")
		)
		(fp_line
			(start 0.508 -0.9398)
			(end 0.508 0.9398)
			(stroke
				(width 0.1524)
				(type default)
			)
			(layer "B.SilkS")
		)
		(fp_rect
			(start 0.508 0.9398)
			(end -0.508 -0.9398)
			(stroke
				(width 0)
				(type default)
			)
			(fill no)
			(layer "B.CrtYd")
		)
		(fp_rect
			(start 0.508 0.9398)
			(end -0.508 -0.9398)
			(stroke
				(width 0)
				(type default)
			)
			(fill no)
			(layer "B.Fab")
		)
		(pad "1" smd custom
			(at 0 -0.4445 180)
			(size 0.1397 0.1397)
			(layers "B.Cu" "B.Mask" "B.Paste")
			(net "ATX_VMONITOR_A1")
			(options
				(clearance outline)
				(anchor circle)
			)
			(primitives
				(gr_poly
					(pts
						(arc
							(start -0.1778 0.2794)
							(mid -0.249642 0.249642)
							(end -0.2794 0.1778)
						)
						(arc
							(start -0.2794 -0.1778)
							(mid -0.249642 -0.249642)
							(end -0.1778 -0.2794)
						)
						(arc
							(start 0.1778 -0.2794)
							(mid 0.249642 -0.249642)
							(end 0.2794 -0.1778)
						)
						(arc
							(start 0.2794 0.1778)
							(mid 0.249642 0.249642)
							(end 0.1778 0.2794)
						)
					)
					(width 0)
					(fill yes)
				)
			)
		)
		(pad "2" smd custom
			(at 0 0.4445 180)
			(size 0.1397 0.1397)
			(layers "B.Cu" "B.Mask" "B.Paste")
			(net "GND")
			(options
				(clearance outline)
				(anchor circle)
			)
			(primitives
				(gr_poly
					(pts
						(arc
							(start -0.1778 0.2794)
							(mid -0.249642 0.249642)
							(end -0.2794 0.1778)
						)
						(arc
							(start -0.2794 -0.1778)
							(mid -0.249642 -0.249642)
							(end -0.1778 -0.2794)
						)
						(arc
							(start 0.1778 -0.2794)
							(mid 0.249642 -0.249642)
							(end 0.2794 -0.1778)
						)
						(arc
							(start 0.2794 0.1778)
							(mid 0.249642 0.249642)
							(end 0.1778 0.2794)
						)
					)
					(width 0)
					(fill yes)
				)
			)
		)
	)
	(footprint ""
		(layer "B.Cu")
		(at 18.6182 -21.0058 90)
		(property "Reference" "C56"
			(at 0 0 90)
			(layer "B.SilkS")
			(hide yes)
			(effects
				(font
					(size 1.27 1.27)
				)
				(justify mirror)
			)
		)
		(property "Value" "SCD1U25V2KX-2-GP"
			(at -1.1811 -2.7051 90)
			(unlocked yes)
			(layer "B.Fab")
			(hide yes)
			(effects
				(font
					(size 1.016 1.016)
					(thickness 0.1524)
				)
				(justify mirror)
			)
		)
		(property "Device Type" "C402H22"
			(at -1.1811 -4.2291 90)
			(unlocked yes)
			(layer "B.Fab")
			(hide yes)
			(effects
				(font
					(size 1.016 1.016)
					(thickness 0.1524)
				)
				(justify mirror)
			)
		)
		(duplicate_pad_numbers_are_jumpers no)
		(fp_rect
			(start 0.4318 0.9525)
			(end -0.4318 -0.9525)
			(stroke
				(width 0)
				(type default)
			)
			(fill no)
			(layer "B.CrtYd")
		)
		(fp_rect
			(start 0.4318 0.9525)
			(end -0.4318 -0.9525)
			(stroke
				(width 0)
				(type default)
			)
			(fill no)
			(layer "B.Fab")
		)
		(pad "1" smd custom
			(at 0 -0.4445 270)
			(size 0.1524 0.1524)
			(layers "B.Cu" "B.Mask" "B.Paste")
			(net "P12V")
			(options
				(clearance outline)
				(anchor circle)
			)
			(primitives
				(gr_poly
					(pts
						(arc
							(start 0.3048 0.2032)
							(mid 0.275042 0.275042)
							(end 0.2032 0.3048)
						)
						(arc
							(start -0.2032 0.3048)
							(mid -0.275042 0.275042)
							(end -0.3048 0.2032)
						)
						(arc
							(start -0.3048 -0.2032)
							(mid -0.275042 -0.275042)
							(end -0.2032 -0.3048)
						)
						(arc
							(start 0.2032 -0.3048)
							(mid 0.275042 -0.275042)
							(end 0.3048 -0.2032)
						)
					)
					(width 0)
					(fill yes)
				)
			)
		)
		(pad "2" smd custom
			(at 0 0.4445 270)
			(size 0.1524 0.1524)
			(layers "B.Cu" "B.Mask" "B.Paste")
			(net "GND")
			(options
				(clearance outline)
				(anchor circle)
			)
			(primitives
				(gr_poly
					(pts
						(arc
							(start 0.3048 0.2032)
							(mid 0.275042 0.275042)
							(end 0.2032 0.3048)
						)
						(arc
							(start -0.2032 0.3048)
							(mid -0.275042 0.275042)
							(end -0.3048 0.2032)
						)
						(arc
							(start -0.3048 -0.2032)
							(mid -0.275042 -0.275042)
							(end -0.2032 -0.3048)
						)
						(arc
							(start 0.2032 -0.3048)
							(mid 0.275042 -0.275042)
							(end 0.3048 -0.2032)
						)
					)
					(width 0)
					(fill yes)
				)
			)
		)
	)
	(footprint ""
		(layer "B.Cu")
		(at 121.5898 -30.099 90)
		(property "Reference" "CU3"
			(at 0 0 90)
			(layer "B.SilkS")
			(hide yes)
			(effects
				(font
					(size 1.27 1.27)
				)
				(justify mirror)
			)
		)
		(property "Value" "SC1U10V2KX-4-GP"
			(at -1.1811 -2.7051 90)
			(unlocked yes)
			(layer "B.Fab")
			(hide yes)
			(effects
				(font
					(size 1.016 1.016)
					(thickness 0.1524)
				)
				(justify mirror)
			)
		)
		(property "Device Type" "C402H22"
			(at -1.1811 -4.2291 90)
			(unlocked yes)
			(layer "B.Fab")
			(hide yes)
			(effects
				(font
					(size 1.016 1.016)
					(thickness 0.1524)
				)
				(justify mirror)
			)
		)
		(duplicate_pad_numbers_are_jumpers no)
		(fp_rect
			(start 0.4318 0.9525)
			(end -0.4318 -0.9525)
			(stroke
				(width 0)
				(type default)
			)
			(fill no)
			(layer "B.CrtYd")
		)
		(fp_rect
			(start 0.4318 0.9525)
			(end -0.4318 -0.9525)
			(stroke
				(width 0)
				(type default)
			)
			(fill no)
			(layer "B.Fab")
		)
		(pad "1" smd custom
			(at 0 -0.4445 270)
			(size 0.1524 0.1524)
			(layers "B.Cu" "B.Mask" "B.Paste")
			(net "P3V3_USB_HUB")
			(options
				(clearance outline)
				(anchor circle)
			)
			(primitives
				(gr_poly
					(pts
						(arc
							(start 0.3048 0.2032)
							(mid 0.275042 0.275042)
							(end 0.2032 0.3048)
						)
						(arc
							(start -0.2032 0.3048)
							(mid -0.275042 0.275042)
							(end -0.3048 0.2032)
						)
						(arc
							(start -0.3048 -0.2032)
							(mid -0.275042 -0.275042)
							(end -0.2032 -0.3048)
						)
						(arc
							(start 0.2032 -0.3048)
							(mid 0.275042 -0.275042)
							(end 0.3048 -0.2032)
						)
					)
					(width 0)
					(fill yes)
				)
			)
		)
		(pad "2" smd custom
			(at 0 0.4445 270)
			(size 0.1524 0.1524)
			(layers "B.Cu" "B.Mask" "B.Paste")
			(net "GND")
			(options
				(clearance outline)
				(anchor circle)
			)
			(primitives
				(gr_poly
					(pts
						(arc
							(start 0.3048 0.2032)
							(mid 0.275042 0.275042)
							(end 0.2032 0.3048)
						)
						(arc
							(start -0.2032 0.3048)
							(mid -0.275042 0.275042)
							(end -0.3048 0.2032)
						)
						(arc
							(start -0.3048 -0.2032)
							(mid -0.275042 -0.275042)
							(end -0.2032 -0.3048)
						)
						(arc
							(start 0.2032 -0.3048)
							(mid 0.275042 -0.275042)
							(end 0.3048 -0.2032)
						)
					)
					(width 0)
					(fill yes)
				)
			)
		)
	)
	(footprint ""
		(layer "B.Cu")
		(at 18.3896 -5.5626)
		(property "Reference" "PC4"
			(at 0 0 0)
			(layer "B.SilkS")
			(hide yes)
			(effects
				(font
					(size 1.27 1.27)
				)
				(justify mirror)
			)
		)
		(property "Value" "SCD1U50V3KX-GP"
			(at 0 -2.8194 0)
			(unlocked yes)
			(layer "B.Fab")
			(hide yes)
			(effects
				(font
					(size 1.016 1.016)
					(thickness 0.1524)
				)
				(justify mirror)
			)
		)
		(property "Device Type" "C603H36"
			(at 0 -4.3434 0)
			(unlocked yes)
			(layer "B.Fab")
			(hide yes)
			(effects
				(font
					(size 1.016 1.016)
					(thickness 0.1524)
				)
				(justify mirror)
			)
		)
		(duplicate_pad_numbers_are_jumpers no)
		(fp_line
			(start -0.508 0)
			(end 0.508 0)
			(stroke
				(width 0.2032)
				(type default)
			)
			(layer "B.SilkS")
		)
		(fp_rect
			(start 0.5842 1.3335)
			(end -0.5842 -1.3335)
			(stroke
				(width 0)
				(type default)
			)
			(fill no)
			(layer "B.CrtYd")
		)
		(fp_rect
			(start 0.5842 1.3335)
			(end -0.5842 -1.3335)
			(stroke
				(width 0)
				(type default)
			)
			(fill no)
			(layer "B.Fab")
		)
		(pad "1" smd custom
			(at 0 -0.762 180)
			(size 0.2159 0.2159)
			(layers "B.Cu" "B.Mask" "B.Paste")
			(net "P3V3_BST")
			(options
				(clearance outline)
				(anchor circle)
			)
			(primitives
				(gr_poly
					(pts
						(arc
							(start -0.3302 0.4318)
							(mid -0.402042 0.402042)
							(end -0.4318 0.3302)
						)
						(arc
							(start -0.4318 -0.3302)
							(mid -0.402042 -0.402042)
							(end -0.3302 -0.4318)
						)
						(arc
							(start 0.3302 -0.4318)
							(mid 0.402042 -0.402042)
							(end 0.4318 -0.3302)
						)
						(arc
							(start 0.4318 0.3302)
							(mid 0.402042 0.402042)
							(end 0.3302 0.4318)
						)
					)
					(width 0)
					(fill yes)
				)
			)
		)
		(pad "2" smd custom
			(at 0 0.762 180)
			(size 0.2159 0.2159)
			(layers "B.Cu" "B.Mask" "B.Paste")
			(net "P3V3_SW")
			(options
				(clearance outline)
				(anchor circle)
			)
			(primitives
				(gr_poly
					(pts
						(arc
							(start -0.3302 0.4318)
							(mid -0.402042 0.402042)
							(end -0.4318 0.3302)
						)
						(arc
							(start -0.4318 -0.3302)
							(mid -0.402042 -0.402042)
							(end -0.3302 -0.4318)
						)
						(arc
							(start 0.3302 -0.4318)
							(mid 0.402042 -0.402042)
							(end 0.4318 -0.3302)
						)
						(arc
							(start 0.4318 0.3302)
							(mid 0.402042 0.402042)
							(end 0.3302 0.4318)
						)
					)
					(width 0)
					(fill yes)
				)
			)
		)
	)
)
